(kicad_pcb
	(version 20260206)
	(generator "pcbnew")
	(generator_version "10.0")
	(general
		(thickness 1.6)
		(legacy_teardrops no)
	)
	(paper "A4")
	(title_block
		(title "Bryce Canyon_F.DPB_16315-1-OCP.brd")
		(comment 1 "Bryce Canyon / footprints 1165-1168 of 2223")
	)
	(layers
		(0 "F.Cu" signal "TOP")
		(4 "In1.Cu" signal "L2GND")
		(6 "In2.Cu" signal "L3")
		(8 "In3.Cu" signal "L4GND")
		(10 "In4.Cu" signal "L5")
		(12 "In5.Cu" signal "L6VCC")
		(14 "In6.Cu" signal "L7VCC")
		(16 "In7.Cu" signal "L8")
		(18 "In8.Cu" signal "L9GND")
		(20 "In9.Cu" signal "L10")
		(22 "In10.Cu" signal "L11GND")
		(2 "B.Cu" signal "BOTTOM")
		(9 "F.Adhes" user "F.Adhesive")
		(11 "B.Adhes" user "B.Adhesive")
		(13 "F.Paste" user "Package Geometry/Pastemask Top")
		(15 "B.Paste" user "Package Geometry/Pastemask Bottom")
		(5 "F.SilkS" user "Ref Des/Silkscreen Top")
		(7 "B.SilkS" user "Ref Des/Silkscreen Bottom")
		(1 "F.Mask" user "Board Geometry/Soldermask Top")
		(3 "B.Mask" user "Board Geometry/Soldermask Bottom")
		(17 "Dwgs.User" user "User.Drawings")
		(19 "Cmts.User" user "User.Comments")
		(21 "Eco1.User" user "User.Eco1")
		(23 "Eco2.User" user "User.Eco2")
		(25 "Edge.Cuts" user "Board Geometry/Outline")
		(27 "Margin" user)
		(31 "F.CrtYd" user "Package Geometry/Place Bound Top")
		(29 "B.CrtYd" user "Package Geometry/Place Bound Bottom")
		(35 "F.Fab" user "Ref Des/Assembly Top")
		(33 "B.Fab" user "Ref Des/Assembly Bottom")
	)
	(footprint ""
		(layer "F.Cu")
		(at 357.100124 -287.910016 -90)
		(property "Reference" "HDDSAS7"
			(at 0 0 270)
			(layer "F.SilkS")
			(hide yes)
			(effects
				(font
					(size 1.27 1.27)
				)
			)
		)
		(property "Value" "SKT-SAS15P-14P-45-GP"
			(at -20.7645 -8.9789 270)
			(unlocked yes)
			(layer "F.Fab")
			(hide yes)
			(effects
				(font
					(size 1.016 1.016)
					(thickness 0.1524)
				)
			)
		)
		(property "Device Type" "10120818-001C-TRLF"
			(at -20.7645 -10.5029 270)
			(unlocked yes)
			(layer "F.Fab")
			(hide yes)
			(effects
				(font
					(size 1.016 1.016)
					(thickness 0.1524)
				)
			)
		)
		(duplicate_pad_numbers_are_jumpers no)
		(fp_line
			(start 1.651 4.2926)
			(end 1.651 3.0099)
			(stroke
				(width 0.1524)
				(type default)
			)
			(layer "F.SilkS")
		)
		(fp_line
			(start 8.509 4.2926)
			(end 1.651 4.2926)
			(stroke
				(width 0.1524)
				(type default)
			)
			(layer "F.SilkS")
		)
		(fp_line
			(start -23.4188 3.0099)
			(end -23.4188 -3.2512)
			(stroke
				(width 0.1524)
				(type default)
			)
			(layer "F.SilkS")
		)
		(fp_line
			(start 1.651 3.0099)
			(end -23.4188 3.0099)
			(stroke
				(width 0.1524)
				(type default)
			)
			(layer "F.SilkS")
		)
		(fp_line
			(start 8.509 3.0099)
			(end 8.509 4.2926)
			(stroke
				(width 0.1524)
				(type default)
			)
			(layer "F.SilkS")
		)
		(fp_line
			(start 23.4188 3.0099)
			(end 8.509 3.0099)
			(stroke
				(width 0.1524)
				(type default)
			)
			(layer "F.SilkS")
		)
		(fp_line
			(start -23.4188 -3.2512)
			(end 23.4188 -3.2512)
			(stroke
				(width 0.1524)
				(type default)
			)
			(layer "F.SilkS")
		)
		(fp_line
			(start 23.4188 -3.2512)
			(end 23.4188 3.0099)
			(stroke
				(width 0.1524)
				(type default)
			)
			(layer "F.SilkS")
		)
		(fp_line
			(start 15.5067 -3.3401)
			(end 16.2687 -3.3401)
			(stroke
				(width 0.3302)
				(type default)
			)
			(layer "F.SilkS")
		)
		(fp_poly
			(pts
				(xy 15.868904 -3.230372) (xy 16.503904 -3.865372) (xy 15.233904 -3.865372)
			)
			(stroke
				(width 0)
				(type default)
			)
			(fill yes)
			(layer "F.SilkS")
		)
		(fp_poly
			(pts
				(xy -22.8727 -2.7559) (xy 22.8727 -2.7559) (xy 22.8727 2.7559) (xy 8.255 2.7559) (xy 8.255 3.5179)
				(xy 1.905 3.5179) (xy 1.905 2.7559) (xy -22.8727 2.7559)
			)
			(stroke
				(width 0)
				(type default)
			)
			(fill no)
			(layer "F.CrtYd")
		)
		(fp_poly
			(pts
				(xy 1.397 4.5466) (xy 1.397 3.2639) (xy -23.6728 3.2639) (xy -23.6728 -3.5052) (xy 23.6728 -3.5052)
				(xy 23.6728 -0.00635) (xy 22.8727 -0.00635) (xy 22.8727 -2.7559) (xy -22.8727 -2.7559) (xy -22.8727 2.7559)
				(xy 1.905 2.7559) (xy 1.905 3.5179) (xy 8.255 3.5179) (xy 8.255 2.7559) (xy 22.8727 2.7559) (xy 22.8727 0.00635)
				(xy 23.6728 0.00635) (xy 23.6728 3.2639) (xy 8.763 3.2639) (xy 8.763 4.5466)
			)
			(stroke
				(width 0)
				(type default)
			)
			(fill no)
			(layer "F.CrtYd")
		)
		(fp_poly
			(pts
				(xy 1.397 4.5466) (xy 1.397 3.2639) (xy -23.6728 3.2639) (xy -23.6728 -3.5052) (xy 23.6728 -3.5052)
				(xy 23.6728 3.2639) (xy 8.763 3.2639) (xy 8.763 4.5466)
			)
			(stroke
				(width 0)
				(type default)
			)
			(fill no)
			(layer "F.Fab")
		)
		(pad "" np_thru_hole circle
			(at -18.874994 0 270)
			(size 0.254 0.254)
			(drill 1.3462)
			(layers "*.Cu" "*.Mask")
			(clearance 0.9017)
			(thermal_gap 0.9017)
		)
		(pad "" np_thru_hole circle
			(at 18.874994 0 270)
			(size 0.254 0.254)
			(drill 0.9398)
			(layers "*.Cu" "*.Mask")
			(clearance 0.6985)
			(thermal_gap 0.6985)
		)
		(pad "G1" smd rect
			(at 21.874988 0 270)
			(size 2.5908 2.5908)
			(layers "F.Cu" "F.Mask" "F.Paste")
			(net "GND")
		)
		(pad "G2" smd rect
			(at -21.874988 0 270)
			(size 2.5908 2.5908)
			(layers "F.Cu" "F.Mask" "F.Paste")
			(net "GND")
		)
		(pad "P1" smd rect
			(at 1.905 -1.82499 270)
			(size 0.6096 2.3622)
			(layers "F.Cu" "F.Mask" "F.Paste")
			(net "Net_2006")
		)
		(pad "P2" smd rect
			(at 0.635 -1.82499 270)
			(size 0.6096 2.3622)
			(layers "F.Cu" "F.Mask" "F.Paste")
			(net "Net_2007")
		)
		(pad "P3" smd rect
			(at -0.635 -1.82499 270)
			(size 0.6096 2.3622)
			(layers "F.Cu" "F.Mask" "F.Paste")
			(net "Net_2008")
		)
		(pad "P4" smd rect
			(at -1.905 -1.82499 270)
			(size 0.6096 2.3622)
			(layers "F.Cu" "F.Mask" "F.Paste")
			(net "GND")
		)
		(pad "P5" smd rect
			(at -3.175 -1.82499 270)
			(size 0.6096 2.3622)
			(layers "F.Cu" "F.Mask" "F.Paste")
			(net "HDD_PRSNT_7")
		)
		(pad "P6" smd rect
			(at -4.445 -1.82499 270)
			(size 0.6096 2.3622)
			(layers "F.Cu" "F.Mask" "F.Paste")
			(net "GND")
		)
		(pad "P7" smd rect
			(at -5.715 -1.82499 270)
			(size 0.6096 2.3622)
			(layers "F.Cu" "F.Mask" "F.Paste")
			(net "5V_PRE_7")
		)
		(pad "P8" smd rect
			(at -6.985 -1.82499 270)
			(size 0.6096 2.3622)
			(layers "F.Cu" "F.Mask" "F.Paste")
			(net "P5V_HDD7")
		)
		(pad "P9" smd rect
			(at -8.255 -1.82499 270)
			(size 0.6096 2.3622)
			(layers "F.Cu" "F.Mask" "F.Paste")
			(net "P5V_HDD7")
		)
		(pad "P10" smd rect
			(at -9.525 -1.82499 270)
			(size 0.6096 2.3622)
			(layers "F.Cu" "F.Mask" "F.Paste")
			(net "GND")
		)
		(pad "P11" smd rect
			(at -10.795 -1.82499 270)
			(size 0.6096 2.3622)
			(layers "F.Cu" "F.Mask" "F.Paste")
			(net "ACT_HDD_7")
		)
		(pad "P12" smd rect
			(at -12.065 -1.82499 270)
			(size 0.6096 2.3622)
			(layers "F.Cu" "F.Mask" "F.Paste")
			(net "GND")
		)
		(pad "P13" smd rect
			(at -13.335 -1.82499 270)
			(size 0.6096 2.3622)
			(layers "F.Cu" "F.Mask" "F.Paste")
			(net "12V_PRE_7")
		)
		(pad "P14" smd rect
			(at -14.605 -1.82499 270)
			(size 0.6096 2.3622)
			(layers "F.Cu" "F.Mask" "F.Paste")
			(net "P12V_HDD7")
		)
		(pad "P15" smd rect
			(at -15.875 -1.82499 270)
			(size 0.6096 2.3622)
			(layers "F.Cu" "F.Mask" "F.Paste")
			(net "P12V_HDD7")
		)
		(pad "S1" smd rect
			(at 15.875 -1.82499 270)
			(size 0.6096 2.3622)
			(layers "F.Cu" "F.Mask" "F.Paste")
			(net "GND")
		)
		(pad "S2" smd rect
			(at 14.605 -1.82499 270)
			(size 0.6096 2.3622)
			(layers "F.Cu" "F.Mask" "F.Paste")
			(net "SAS_HDD_RX_P7")
		)
		(pad "S3" smd rect
			(at 13.335 -1.82499 270)
			(size 0.6096 2.3622)
			(layers "F.Cu" "F.Mask" "F.Paste")
			(net "SAS_HDD_RX_N7")
		)
		(pad "S4" smd rect
			(at 12.065 -1.82499 270)
			(size 0.6096 2.3622)
			(layers "F.Cu" "F.Mask" "F.Paste")
			(net "GND")
		)
		(pad "S5" smd rect
			(at 10.795 -1.82499 270)
			(size 0.6096 2.3622)
			(layers "F.Cu" "F.Mask" "F.Paste")
			(net "PHY_DRV_A_TO_SCC_A_7_DN")
		)
		(pad "S6" smd rect
			(at 9.525 -1.82499 270)
			(size 0.6096 2.3622)
			(layers "F.Cu" "F.Mask" "F.Paste")
			(net "PHY_DRV_A_TO_SCC_A_7_DP")
		)
		(pad "S7" smd rect
			(at 8.255 -1.82499 270)
			(size 0.6096 2.3622)
			(layers "F.Cu" "F.Mask" "F.Paste")
			(net "GND")
		)
		(pad "S8" smd rect
			(at 7.480046 2.845054 270)
			(size 0.508 2.3622)
			(layers "F.Cu" "F.Mask" "F.Paste")
			(net "GND")
		)
		(pad "S9" smd rect
			(at 6.679946 2.845054 270)
			(size 0.508 2.3622)
			(layers "F.Cu" "F.Mask" "F.Paste")
			(net "Net_479")
		)
		(pad "S10" smd rect
			(at 5.8801 2.845054 270)
			(size 0.508 2.3622)
			(layers "F.Cu" "F.Mask" "F.Paste")
			(net "Net_371")
		)
		(pad "S11" smd rect
			(at 5.08 2.845054 270)
			(size 0.508 2.3622)
			(layers "F.Cu" "F.Mask" "F.Paste")
			(net "GND")
		)
		(pad "S12" smd rect
			(at 4.2799 2.845054 270)
			(size 0.508 2.3622)
			(layers "F.Cu" "F.Mask" "F.Paste")
			(net "Net_407")
		)
		(pad "S13" smd rect
			(at 3.480054 2.845054 270)
			(size 0.508 2.3622)
			(layers "F.Cu" "F.Mask" "F.Paste")
			(net "Net_443")
		)
		(pad "S14" smd rect
			(at 2.679954 2.845054 270)
			(size 0.508 2.3622)
			(layers "F.Cu" "F.Mask" "F.Paste")
			(net "GND")
		)
		(zone
			(layer "F.Cu")
			(hatch none 0.5)
			(connect_pads
				(clearance 0)
			)
			(min_thickness 0.25)
			(keepout
				(tracks allowed)
				(vias not_allowed)
				(pads allowed)
				(copperpour not_allowed)
				(footprints allowed)
			)
			(placement
				(enabled no)
				(sheetname "")
			)
			(fill
				(thermal_gap 0.5)
				(thermal_bridge_width 0.5)
				(island_removal_mode 0)
			)
			(polygon
				(pts
					(xy 360.757724 -304.648616) (xy 353.683824 -304.648616) (xy 353.683824 -311.582816) (xy 354.788724 -311.582816)
					(xy 354.788724 -307.468016) (xy 359.411524 -307.468016) (xy 359.411524 -311.582816) (xy 360.757724 -311.582816)
				)
			)
		)
		(zone
			(layer "F.Cu")
			(hatch none 0.5)
			(connect_pads
				(clearance 0)
			)
			(min_thickness 0.25)
			(keepout
				(tracks not_allowed)
				(vias allowed)
				(pads allowed)
				(copperpour not_allowed)
				(footprints allowed)
			)
			(placement
				(enabled no)
				(sheetname "")
			)
			(fill
				(thermal_gap 0.5)
				(thermal_bridge_width 0.5)
				(island_removal_mode 0)
			)
			(polygon
				(pts
					(xy 360.757724 -304.648616) (xy 353.683824 -304.648616) (xy 353.683824 -311.582816) (xy 354.788724 -311.582816)
					(xy 354.788724 -307.468016) (xy 359.411524 -307.468016) (xy 359.411524 -311.582816) (xy 360.757724 -311.582816)
				)
			)
		)
		(zone
			(layer "F.Cu")
			(hatch none 0.5)
			(connect_pads
				(clearance 0)
			)
			(min_thickness 0.25)
			(keepout
				(tracks not_allowed)
				(vias allowed)
				(pads allowed)
				(copperpour not_allowed)
				(footprints allowed)
			)
			(placement
				(enabled no)
				(sheetname "")
			)
			(fill
				(thermal_gap 0.5)
				(thermal_bridge_width 0.5)
				(island_removal_mode 0)
			)
			(polygon
				(pts
					(xy 360.757724 -271.171416) (xy 353.683824 -271.171416) (xy 353.683824 -264.237216) (xy 354.788724 -264.237216)
					(xy 354.788724 -268.352016) (xy 359.411524 -268.352016) (xy 359.411524 -264.237216) (xy 360.757724 -264.237216)
				)
			)
		)
		(zone
			(layer "F.Cu")
			(hatch none 0.5)
			(connect_pads
				(clearance 0)
			)
			(min_thickness 0.25)
			(keepout
				(tracks allowed)
				(vias not_allowed)
				(pads allowed)
				(copperpour not_allowed)
				(footprints allowed)
			)
			(placement
				(enabled no)
				(sheetname "")
			)
			(fill
				(thermal_gap 0.5)
				(thermal_bridge_width 0.5)
				(island_removal_mode 0)
			)
			(polygon
				(pts
					(xy 360.757724 -271.171416) (xy 353.683824 -271.171416) (xy 353.683824 -264.237216) (xy 354.788724 -264.237216)
					(xy 354.788724 -268.352016) (xy 359.411524 -268.352016) (xy 359.411524 -264.237216) (xy 360.757724 -264.237216)
				)
			)
		)
		(zone
			(layers "F.Cu" "B.Cu" "In1.Cu" "In2.Cu" "In3.Cu" "In4.Cu" "In5.Cu" "In6.Cu"
				"In7.Cu" "In8.Cu" "In9.Cu" "In10.Cu"
			)
			(hatch none 0.5)
			(connect_pads
				(clearance 0)
			)
			(min_thickness 0.25)
			(keepout
				(tracks not_allowed)
				(vias allowed)
				(pads allowed)
				(copperpour not_allowed)
				(footprints allowed)
			)
			(placement
				(enabled no)
				(sheetname "")
			)
			(fill
				(thermal_gap 0.5)
				(thermal_bridge_width 0.5)
				(island_removal_mode 0)
			)
			(polygon
				(pts
					(arc
						(start 357.874824 -269.035022)
						(mid 356.325424 -269.035022)
						(end 357.874824 -269.035022)
					)
				)
			)
		)
		(zone
			(layers "F.Cu" "B.Cu" "In1.Cu" "In2.Cu" "In3.Cu" "In4.Cu" "In5.Cu" "In6.Cu"
				"In7.Cu" "In8.Cu" "In9.Cu" "In10.Cu"
			)
			(hatch none 0.5)
			(connect_pads
				(clearance 0)
			)
			(min_thickness 0.25)
			(keepout
				(tracks not_allowed)
				(vias allowed)
				(pads allowed)
				(copperpour not_allowed)
				(footprints allowed)
			)
			(placement
				(enabled no)
				(sheetname "")
			)
			(fill
				(thermal_gap 0.5)
				(thermal_bridge_width 0.5)
				(island_removal_mode 0)
			)
			(polygon
				(pts
					(arc
						(start 358.078024 -306.78501)
						(mid 356.122224 -306.78501)
						(end 358.078024 -306.78501)
					)
				)
			)
		)
	)
	(footprint ""
		(layer "F.Cu")
		(at 141.017498 -160.608518 90)
		(property "Reference" "R512"
			(at 0 0 90)
			(layer "F.SilkS")
			(hide yes)
			(effects
				(font
					(size 1.27 1.27)
				)
			)
		)
		(property "Value" "4K7R2J-2-GP"
			(at 0.064008 -3.993896 90)
			(unlocked yes)
			(layer "F.Fab")
			(hide yes)
			(effects
				(font
					(size 1.016 1.016)
					(thickness 0.1524)
				)
			)
		)
		(property "Device Type" "R402H16"
			(at 0.064008 -5.517896 90)
			(unlocked yes)
			(layer "F.Fab")
			(hide yes)
			(effects
				(font
					(size 1.016 1.016)
					(thickness 0.1524)
				)
			)
		)
		(duplicate_pad_numbers_are_jumpers no)
		(fp_line
			(start 0.508 -0.9398)
			(end -0.508 -0.9398)
			(stroke
				(width 0.1524)
				(type default)
			)
			(layer "F.SilkS")
		)
		(fp_line
			(start -0.508 -0.9398)
			(end -0.508 0.9398)
			(stroke
				(width 0.1524)
				(type default)
			)
			(layer "F.SilkS")
		)
		(fp_rect
			(start -0.508 0.9398)
			(end 0.508 -0.9398)
			(stroke
				(width 0)
				(type default)
			)
			(fill no)
			(layer "F.CrtYd")
		)
		(fp_rect
			(start -0.508 0.9398)
			(end 0.508 -0.9398)
			(stroke
				(width 0)
				(type default)
			)
			(fill no)
			(layer "F.Fab")
		)
		(pad "1" smd custom
			(at 0 -0.4445 90)
			(size 0.1397 0.1397)
			(layers "F.Cu" "F.Mask" "F.Paste")
			(net "P12V_A")
			(options
				(clearance outline)
				(anchor circle)
			)
			(primitives
				(gr_poly
					(pts
						(arc
							(start -0.1778 -0.2794)
							(mid -0.249642 -0.249642)
							(end -0.2794 -0.1778)
						)
						(arc
							(start -0.2794 0.1778)
							(mid -0.249642 0.249642)
							(end -0.1778 0.2794)
						)
						(arc
							(start 0.1778 0.2794)
							(mid 0.249642 0.249642)
							(end 0.2794 0.1778)
						)
						(arc
							(start 0.2794 -0.1778)
							(mid 0.249642 -0.249642)
							(end 0.1778 -0.2794)
						)
					)
					(width 0)
					(fill yes)
				)
			)
		)
		(pad "2" smd custom
			(at 0 0.4445 90)
			(size 0.1397 0.1397)
			(layers "F.Cu" "F.Mask" "F.Paste")
			(net "SW_HDD_R16")
			(options
				(clearance outline)
				(anchor circle)
			)
			(primitives
				(gr_poly
					(pts
						(arc
							(start -0.1778 -0.2794)
							(mid -0.249642 -0.249642)
							(end -0.2794 -0.1778)
						)
						(arc
							(start -0.2794 0.1778)
							(mid -0.249642 0.249642)
							(end -0.1778 0.2794)
						)
						(arc
							(start 0.1778 0.2794)
							(mid 0.249642 0.249642)
							(end 0.2794 0.1778)
						)
						(arc
							(start 0.2794 -0.1778)
							(mid 0.249642 -0.249642)
							(end 0.1778 -0.2794)
						)
					)
					(width 0)
					(fill yes)
				)
			)
		)
	)
	(footprint ""
		(layer "F.Cu")
		(at 181.991 -74.462894 180)
		(property "Reference" "C424"
			(at 0 0 180)
			(layer "F.SilkS")
			(hide yes)
			(effects
				(font
					(size 1.27 1.27)
				)
			)
		)
		(property "Value" "SC1U25V3KX-GP"
			(at 0 -2.8194 180)
			(unlocked yes)
			(layer "F.Fab")
			(hide yes)
			(effects
				(font
					(size 1.016 1.016)
					(thickness 0.1524)
				)
			)
		)
		(property "Device Type" "C603H36"
			(at 0 -4.3434 180)
			(unlocked yes)
			(layer "F.Fab")
			(hide yes)
			(effects
				(font
					(size 1.016 1.016)
					(thickness 0.1524)
				)
			)
		)
		(duplicate_pad_numbers_are_jumpers no)
		(fp_line
			(start 0.508 0)
			(end -0.508 0)
			(stroke
				(width 0.2032)
				(type default)
			)
			(layer "F.SilkS")
		)
		(fp_rect
			(start -0.5842 1.3335)
			(end 0.5842 -1.3335)
			(stroke
				(width 0)
				(type default)
			)
			(fill no)
			(layer "F.CrtYd")
		)
		(fp_rect
			(start -0.5842 1.3335)
			(end 0.5842 -1.3335)
			(stroke
				(width 0)
				(type default)
			)
			(fill no)
			(layer "F.Fab")
		)
		(pad "1" smd custom
			(at 0 -0.762 180)
			(size 0.2159 0.2159)
			(layers "F.Cu" "F.Mask" "F.Paste")
			(net "P12V_HDD29")
			(options
				(clearance outline)
				(anchor circle)
			)
			(primitives
				(gr_poly
					(pts
						(arc
							(start -0.3302 -0.4318)
							(mid -0.402042 -0.402042)
							(end -0.4318 -0.3302)
						)
						(arc
							(start -0.4318 0.3302)
							(mid -0.402042 0.402042)
							(end -0.3302 0.4318)
						)
						(arc
							(start 0.3302 0.4318)
							(mid 0.402042 0.402042)
							(end 0.4318 0.3302)
						)
						(arc
							(start 0.4318 -0.3302)
							(mid 0.402042 -0.402042)
							(end 0.3302 -0.4318)
						)
					)
					(width 0)
					(fill yes)
				)
			)
		)
		(pad "2" smd custom
			(at 0 0.762 180)
			(size 0.2159 0.2159)
			(layers "F.Cu" "F.Mask" "F.Paste")
			(net "GND")
			(options
				(clearance outline)
				(anchor circle)
			)
			(primitives
				(gr_poly
					(pts
						(arc
							(start -0.3302 -0.4318)
							(mid -0.402042 -0.402042)
							(end -0.4318 -0.3302)
						)
						(arc
							(start -0.4318 0.3302)
							(mid -0.402042 0.402042)
							(end -0.3302 0.4318)
						)
						(arc
							(start 0.3302 0.4318)
							(mid 0.402042 0.402042)
							(end 0.4318 0.3302)
						)
						(arc
							(start 0.4318 -0.3302)
							(mid 0.402042 -0.402042)
							(end 0.3302 -0.4318)
						)
					)
					(width 0)
					(fill yes)
				)
			)
		)
	)
	(footprint ""
		(layer "F.Cu")
		(at 161.7472 -298.704)
		(property "Reference" "TP22"
			(at 0 0 0)
			(layer "F.SilkS")
			(hide yes)
			(effects
				(font
					(size 1.27 1.27)
				)
			)
		)
		(property "Value" "TPAD32-GP"
			(at -0.0508 -1.6764 0)
			(unlocked yes)
			(layer "F.Fab")
			(hide yes)
			(effects
				(font
					(size 1.016 1.016)
					(thickness 0.1524)
				)
			)
		)
		(property "Device Type" "TPAD32"
			(at -0.0508 -3.2004 0)
			(unlocked yes)
			(layer "F.Fab")
			(hide yes)
			(effects
				(font
					(size 1.016 1.016)
					(thickness 0.1524)
				)
			)
		)
		(duplicate_pad_numbers_are_jumpers no)
		(fp_poly
			(pts
				(arc
					(start 0.4064 0)
					(mid -0.4064 0)
					(end 0.4064 0)
				)
			)
			(stroke
				(width 0)
				(type default)
			)
			(fill no)
			(layer "F.CrtYd")
		)
		(fp_poly
			(pts
				(arc
					(start 0.7112 0)
					(mid -0.7112 0)
					(end 0.7112 0)
				)
			)
			(stroke
				(width 0)
				(type default)
			)
			(fill no)
			(layer "F.Fab")
		)
		(pad "1" smd circle
			(at 0 0)
			(size 0.8128 0.8128)
			(layers "F.Cu" "F.Mask" "F.Paste")
			(net "ACT_HDD_4")
		)
	)
)
